# BASEBOARD_FAB2 (Tioga Pass) — schematic netlist excerpt (pin names and nets, part order shuffled) for the footprints in the layout excerpt that follows; sources: Cadence DE-HDL packaged netlist, KiCad conversion of Wiwynn_Tioga_Pass_MB.brd

J6L2  SCONN288_H44441003  SCONN  pkg PIP  page 52
  \12v\(1)  = P12V_NVDIMM_DEF
  VSS(93)  = GND
  DQ(4)  = M_E_DQ<4>
  VSS(92)  = GND
  DQ(0)  = M_E_DQ<0>
  VSS(91)  = GND
  DQS9P  = M_E_DQS_DP<9>
  DQS9N  = M_E_DQS_DN<9>
  VSS(90)  = GND
  DQ(6)  = M_E_DQ<6>
  VSS(89)  = GND
  DQ(2)  = M_E_DQ<2>
  VSS(88)  = GND
  DQ(12)  = M_E_DQ<12>
  VSS(87)  = GND
  DQ(8)  = M_E_DQ<8>
  VSS(86)  = GND
  DQS10P  = M_E_DQS_DP<10>
  DQS10N  = M_E_DQS_DN<10>
  VSS(85)  = GND
  DQ(14)  = M_E_DQ<14>
  VSS(84)  = GND
  DQ(10)  = M_E_DQ<10>
  VSS(83)  = GND
  DQ(20)  = M_E_DQ<20>
  VSS(82)  = GND
  DQ(16)  = M_E_DQ<16>
  VSS(81)  = GND
  DQS11P  = M_E_DQS_DP<11>
  DQS11N  = M_E_DQS_DN<11>
  VSS(80)  = GND
  DQ(22)  = M_E_DQ<22>
  VSS(79)  = GND
  DQ(18)  = M_E_DQ<18>
  VSS(78)  = GND
  DQ(28)  = M_E_DQ<28>
  VSS(77)  = GND
  DQ(24)  = M_E_DQ<24>
  VSS(76)  = GND
  DQS12P  = M_E_DQS_DP<12>
  DQS12N  = M_E_DQS_DN<12>
  VSS(75)  = GND
  DQ(30)  = M_E_DQ<30>
  VSS(74)  = GND
  DQ(26)  = M_E_DQ<26>
  VSS(73)  = GND
  CB(4)  = M_E_ECC<4>
  VSS(72)  = GND
  CB(0)  = M_E_ECC<0>
  VSS(71)  = GND
  DQS17P  = M_E_DQS_DP<17>
  DQS17N  = M_E_DQS_DN<17>
  VSS(70)  = GND
  CB(6)  = M_E_ECC<6>
  VSS(69)  = GND
  CB(2)  = M_E_ECC<2>
  VSS(68)  = GND
  RESET_N  = M_DEF_RST_N
  VDD(25)  = PVDDQ_DEF
  CKE(0)  = M_E_CKE<2>
  VDD(24)  = PVDDQ_DEF
  ACT_N  = M_E_ACT_N
  BG(0)  = M_E_BG<0>
  VDD(23)  = PVDDQ_DEF
  A12  = M_E_MA<12>
  A9  = M_E_MA<9>
  VDD(22)  = PVDDQ_DEF
  A8  = M_E_MA<8>
  A6  = M_E_MA<6>
  VDD(21)  = PVDDQ_DEF
  A3  = M_E_MA<3>
  A1  = M_E_MA<1>
  VDD(20)  = PVDDQ_DEF
  CK0P  = M_E_CLK_DP<2>
  CK0N  = M_E_CLK_DN<2>
  VDD(19)  = PVDDQ_DEF
  VTT(1)  = PVTT_DEF
  EVENT_N  = FM_DIMM_EVENT_COD_N
  A0  = M_E_MA<0>
  VDD(18)  = PVDDQ_DEF
  BA(0)  = M_E_BA<0>
  A16_RAS_N  = M_E_MA<16>
  VDD(17)  = PVDDQ_DEF
  S0_N  = M_E_CS_N<4>
  VDD(16)  = PVDDQ_DEF
  A15_CAS_N  = M_E_MA<15>
  ODT(0)  = M_E_ODT<2>
  VDD(15)  = PVDDQ_DEF
  S1_N  = M_E_CS_N<5>
  VDD(14)  = PVDDQ_DEF
  ODT(1)  = M_E_ODT<3>
  VDD(13)  = PVDDQ_DEF
  S2_N_C(0)  = M_E_CS_N<6>
  VSS(67)  = GND
  DQ(36)  = M_E_DQ<36>
  VSS(66)  = GND
  DQ(32)  = M_E_DQ<32>
  VSS(65)  = GND
  DQS13P  = M_E_DQS_DP<13>
  DQS13N  = M_E_DQS_DN<13>
  VSS(64)  = GND
  DQ(38)  = M_E_DQ<38>
  VSS(63)  = GND
  DQ(34)  = M_E_DQ<34>
  VSS(62)  = GND
  DQ(44)  = M_E_DQ<44>
  VSS(61)  = GND
  DQ(40)  = M_E_DQ<40>
  VSS(60)  = GND
  DQS14P  = M_E_DQS_DP<14>
  DQS14N  = M_E_DQS_DN<14>
  VSS(59)  = GND
  DQ(46)  = M_E_DQ<46>
  VSS(58)  = GND
  DQ(42)  = M_E_DQ<42>
  VSS(57)  = GND
  DQ(52)  = M_E_DQ<52>
  VSS(56)  = GND
  DQ(48)  = M_E_DQ<48>
  VSS(55)  = GND
  DQS15P  = M_E_DQS_DP<15>
  DQS15N  = M_E_DQS_DN<15>
  VSS(54)  = GND
  DQ(54)  = M_E_DQ<54>
  VSS(53)  = GND
  DQ(50)  = M_E_DQ<50>
  VSS(52)  = GND
  DQ(60)  = M_E_DQ<60>
  VSS(51)  = GND
  DQ(56)  = M_E_DQ<56>
  VSS(50)  = GND
  DQS16P  = M_E_DQS_DP<16>
  DQS16N  = M_E_DQS_DN<16>
  VSS(49)  = GND
  DQ(62)  = M_E_DQ<62>
  VSS(48)  = GND
  DQ(58)  = M_E_DQ<58>
  VSS(47)  = GND
  SA(0)  = PVPP_DEF
  SA(1)  = PVPP_DEF
  SCL  = SMB_DDR_DEF_VPP_SCL
  VPP(4)  = PVPP_DEF
  VPP(3)  = PVPP_DEF
  RFU(2)  = TP_CH_E_DIMM_E1_RFU_2
  \12v\(0)  = P12V_NVDIMM_DEF
  VREFCA  = M_E_VREF
  VSS(46)  = GND
  DQ(5)  = M_E_DQ<5>
  VSS(45)  = GND
  DQ(1)  = M_E_DQ<1>
  VSS(44)  = GND
  DQS0N  = M_E_DQS_DN<0>
  DQS0P  = M_E_DQS_DP<0>
  VSS(43)  = GND
  DQ(7)  = M_E_DQ<7>
  VSS(42)  = GND
  DQ(3)  = M_E_DQ<3>
  VSS(41)  = GND
  DQ(13)  = M_E_DQ<13>
  VSS(40)  = GND
  DQ(9)  = M_E_DQ<9>
  VSS(39)  = GND
  DQS1N  = M_E_DQS_DN<1>
  DQS1P  = M_E_DQS_DP<1>
  VSS(38)  = GND
  DQ(15)  = M_E_DQ<15>
  VSS(37)  = GND
  DQ(11)  = M_E_DQ<11>
  VSS(36)  = GND
  DQ(21)  = M_E_DQ<21>
  VSS(35)  = GND
  DQ(17)  = M_E_DQ<17>
  VSS(34)  = GND
  DQS2N  = M_E_DQS_DN<2>
  DQS2P  = M_E_DQS_DP<2>
  VSS(33)  = GND
  DQ(23)  = M_E_DQ<23>
  VSS(32)  = GND
  DQ(19)  = M_E_DQ<19>
  VSS(31)  = GND
  DQ(29)  = M_E_DQ<29>
  VSS(30)  = GND
  DQ(25)  = M_E_DQ<25>
  VSS(29)  = GND
  DQS3N  = M_E_DQS_DN<3>
  DQS3P  = M_E_DQS_DP<3>
  VSS(28)  = GND
  DQ(31)  = M_E_DQ<31>
  VSS(27)  = GND
  DQ(27)  = M_E_DQ<27>
  VSS(26)  = GND
  CB(5)  = M_E_ECC<5>
  VSS(25)  = GND
  CB(1)  = M_E_ECC<1>
  VSS(24)  = GND
  DQS8N  = M_E_DQS_DN<8>
  DQS8P  = M_E_DQS_DP<8>
  VSS(23)  = GND
  CB(7)  = M_E_ECC<7>
  VSS(22)  = GND
  CB(3)  = M_E_ECC<3>
  VSS(21)  = GND
  CKE(1)  = M_E_CKE<3>
  VDD(12)  = PVDDQ_DEF
  RFU(0)  = TP_CH_E_DIMM_E1_RFU_0
  VDD(11)  = PVDDQ_DEF
  BG(1)  = M_E_BG<1>
  ALERT_N  = M_E_ALERT_N
  VDD(10)  = PVDDQ_DEF
  A11  = M_E_MA<11>
  A7  = M_E_MA<7>
  VDD(9)  = PVDDQ_DEF
  A5  = M_E_MA<5>
  A4  = M_E_MA<4>
  VDD(8)  = PVDDQ_DEF
  A2  = M_E_MA<2>
  VDD(7)  = PVDDQ_DEF
  CK1P  = M_E_CLK_DP<3>
  CK1N  = M_E_CLK_DN<3>
  VDD(6)  = PVDDQ_DEF
  VTT(0)  = PVTT_DEF
  PAR  = M_E_PAR
  VDD(5)  = PVDDQ_DEF
  BA(1)  = M_E_BA<1>
  A10  = M_E_MA<10>
  VDD(4)  = PVDDQ_DEF
  RFU(1)  = TP_CH_E_DIMM_E1_RFU_1
  A14_WE_N  = M_E_MA<14>
  VDD(3)  = PVDDQ_DEF
  SAVE_N_NC  = FM_ADR_COMPLETE_DEF_N
  VDD(2)  = PVDDQ_DEF
  A13  = M_E_MA<13>
  VDD(1)  = PVDDQ_DEF
  A17  = M_E_MA<17>
  C(2)  = M_E_C<2>
  VDD(0)  = PVDDQ_DEF
  S3_N_C(1)  = M_E_CS_N<7>
  SA(2)  = GND
  VSS(20)  = GND
  DQ(37)  = M_E_DQ<37>
  VSS(19)  = GND
  DQ(33)  = M_E_DQ<33>
  VSS(18)  = GND
  DQS4N  = M_E_DQS_DN<4>
  DQS4P  = M_E_DQS_DP<4>
  VSS(17)  = GND
  DQ(39)  = M_E_DQ<39>
  VSS(16)  = GND
  DQ(35)  = M_E_DQ<35>
  VSS(15)  = GND
  DQ(45)  = M_E_DQ<45>
  VSS(14)  = GND
  DQ(41)  = M_E_DQ<41>
  VSS(13)  = GND
  DQS5N  = M_E_DQS_DN<5>
  DQS5P  = M_E_DQS_DP<5>
  VSS(12)  = GND
  DQ(47)  = M_E_DQ<47>
  VSS(11)  = GND
  DQ(43)  = M_E_DQ<43>
  VSS(10)  = GND
  DQ(53)  = M_E_DQ<53>
  VSS(9)  = GND
  DQ(49)  = M_E_DQ<49>
  VSS(8)  = GND
  DQS6N  = M_E_DQS_DN<6>
  DQS6P  = M_E_DQS_DP<6>
  VSS(7)  = GND
  DQ(55)  = M_E_DQ<55>
  VSS(6)  = GND
  DQ(51)  = M_E_DQ<51>
  VSS(5)  = GND
  DQ(61)  = M_E_DQ<61>
  VSS(4)  = GND
  DQ(57)  = M_E_DQ<57>
  VSS(3)  = GND
  DQS7N  = M_E_DQS_DN<7>
  DQS7P  = M_E_DQS_DP<7>
  VSS(2)  = GND
  DQ(63)  = M_E_DQ<63>
  VSS(1)  = GND
  DQ(59)  = M_E_DQ<59>
  VSS(0)  = GND
  VDDSPD  = PVPP_DEF
  SDA  = SMB_DDR_DEF_VPP_SDA
  VPP(1)  = PVPP_DEF
  VPP(0)  = PVPP_DEF
  VPP(2)  = PVPP_DEF

(kicad_pcb
	(version 20260206)
	(generator "pcbnew")
	(generator_version "10.0")
	(general
		(thickness 1.6)
		(legacy_teardrops no)
	)
	(paper "A4")
	(title_block
		(title "Wiwynn_Tioga_Pass_MB.brd")
		(comment 1 "Tioga Pass / footprint 3319 of 4770 (J6L2), pads 250-291 of 291")
	)
	(layers
		(0 "F.Cu" signal "TOP")
		(4 "In1.Cu" signal "L2GND")
		(6 "In2.Cu" signal "L3")
		(8 "In3.Cu" signal "L4GND")
		(10 "In4.Cu" signal "L5")
		(12 "In5.Cu" signal "L6GND")
		(14 "In6.Cu" signal "L7VCC")
		(16 "In7.Cu" signal "L8VCC")
		(18 "In8.Cu" signal "L9GND")
		(20 "In9.Cu" signal "L10")
		(22 "In10.Cu" signal "L11GND")
		(24 "In11.Cu" signal "L12")
		(26 "In12.Cu" signal "L13GND")
		(2 "B.Cu" signal "BOTTOM")
		(9 "F.Adhes" user "F.Adhesive")
		(11 "B.Adhes" user "B.Adhesive")
		(13 "F.Paste" user "Package Geometry/Pastemask Top")
		(15 "B.Paste" user "Package Geometry/Pastemask Bottom")
		(5 "F.SilkS" user "Ref Des/Silkscreen Top")
		(7 "B.SilkS" user "Ref Des/Silkscreen Bottom")
		(1 "F.Mask" user "Board Geometry/Soldermask Top")
		(3 "B.Mask" user "Board Geometry/Soldermask Bottom")
		(17 "Dwgs.User" user "User.Drawings")
		(19 "Cmts.User" user "User.Comments")
		(21 "Eco1.User" user "User.Eco1")
		(23 "Eco2.User" user "User.Eco2")
		(25 "Edge.Cuts" user "Board Geometry/Outline")
		(27 "Margin" user)
		(31 "F.CrtYd" user "Package Geometry/Place Bound Top")
		(29 "B.CrtYd" user "Package Geometry/Place Bound Bottom")
		(35 "F.Fab" user "Ref Des/Assembly Top")
		(33 "B.Fab" user "Ref Des/Assembly Bottom")
	)
	(footprint ""
		(layer "B.Cu")
		(at 194.700398 -142.477236 90)
		(property "Reference" "J6L2"
			(at 2.276348 38.21811 0)
			(unlocked yes)
			(layer "B.SilkS")
			(effects
				(font
					(size 0.7874 0.5842)
					(thickness 0.1524)
				)
				(justify left mirror)
			)
		)
		(property "Value" ""
			(at 0 0 90)
			(layer "B.Fab")
			(effects
				(font
					(size 1.27 1.27)
				)
				(justify mirror)
			)
		)
		(duplicate_pad_numbers_are_jumpers no)
		(pad "247" smd rect
			(at -4.59994 91.799918 270)
			(size 1.8034 0.508)
			(layers "B.Cu" "B.Mask" "B.Paste")
			(net "M_E_DQ<39>")
		)
		(pad "248" smd rect
			(at -4.59994 92.650056 270)
			(size 1.8034 0.508)
			(layers "B.Cu" "B.Mask" "B.Paste")
			(net "GND")
		)
		(pad "249" smd rect
			(at -4.59994 93.49994 270)
			(size 1.8034 0.508)
			(layers "B.Cu" "B.Mask" "B.Paste")
			(net "M_E_DQ<35>")
		)
		(pad "250" smd rect
			(at -4.59994 94.350078 270)
			(size 1.8034 0.508)
			(layers "B.Cu" "B.Mask" "B.Paste")
			(net "GND")
		)
		(pad "251" smd rect
			(at -4.59994 95.199962 270)
			(size 1.8034 0.508)
			(layers "B.Cu" "B.Mask" "B.Paste")
			(net "M_E_DQ<45>")
		)
		(pad "252" smd rect
			(at -4.59994 96.0501 270)
			(size 1.8034 0.508)
			(layers "B.Cu" "B.Mask" "B.Paste")
			(net "GND")
		)
		(pad "253" smd rect
			(at -4.59994 96.899984 270)
			(size 1.8034 0.508)
			(layers "B.Cu" "B.Mask" "B.Paste")
			(net "M_E_DQ<41>")
		)
		(pad "254" smd rect
			(at -4.59994 97.750122 270)
			(size 1.8034 0.508)
			(layers "B.Cu" "B.Mask" "B.Paste")
			(net "GND")
		)
		(pad "255" smd rect
			(at -4.59994 98.600006 270)
			(size 1.8034 0.508)
			(layers "B.Cu" "B.Mask" "B.Paste")
			(net "M_E_DQS_DN<5>")
		)
		(pad "256" smd rect
			(at -4.59994 99.44989 270)
			(size 1.8034 0.508)
			(layers "B.Cu" "B.Mask" "B.Paste")
			(net "M_E_DQS_DP<5>")
		)
		(pad "257" smd rect
			(at -4.59994 100.300028 270)
			(size 1.8034 0.508)
			(layers "B.Cu" "B.Mask" "B.Paste")
			(net "GND")
		)
		(pad "258" smd rect
			(at -4.59994 101.149912 270)
			(size 1.8034 0.508)
			(layers "B.Cu" "B.Mask" "B.Paste")
			(net "M_E_DQ<47>")
		)
		(pad "259" smd rect
			(at -4.59994 102.00005 270)
			(size 1.8034 0.508)
			(layers "B.Cu" "B.Mask" "B.Paste")
			(net "GND")
		)
		(pad "260" smd rect
			(at -4.59994 102.849934 270)
			(size 1.8034 0.508)
			(layers "B.Cu" "B.Mask" "B.Paste")
			(net "M_E_DQ<43>")
		)
		(pad "261" smd rect
			(at -4.59994 103.700072 270)
			(size 1.8034 0.508)
			(layers "B.Cu" "B.Mask" "B.Paste")
			(net "GND")
		)
		(pad "262" smd rect
			(at -4.59994 104.549956 270)
			(size 1.8034 0.508)
			(layers "B.Cu" "B.Mask" "B.Paste")
			(net "M_E_DQ<53>")
		)
		(pad "263" smd rect
			(at -4.59994 105.400094 270)
			(size 1.8034 0.508)
			(layers "B.Cu" "B.Mask" "B.Paste")
			(net "GND")
		)
		(pad "264" smd rect
			(at -4.59994 106.249978 270)
			(size 1.8034 0.508)
			(layers "B.Cu" "B.Mask" "B.Paste")
			(net "M_E_DQ<49>")
		)
		(pad "265" smd rect
			(at -4.59994 107.100116 270)
			(size 1.8034 0.508)
			(layers "B.Cu" "B.Mask" "B.Paste")
			(net "GND")
		)
		(pad "266" smd rect
			(at -4.59994 107.95 270)
			(size 1.8034 0.508)
			(layers "B.Cu" "B.Mask" "B.Paste")
			(net "M_E_DQS_DN<6>")
		)
		(pad "267" smd rect
			(at -4.59994 108.799884 270)
			(size 1.8034 0.508)
			(layers "B.Cu" "B.Mask" "B.Paste")
			(net "M_E_DQS_DP<6>")
		)
		(pad "268" smd rect
			(at -4.59994 109.650022 270)
			(size 1.8034 0.508)
			(layers "B.Cu" "B.Mask" "B.Paste")
			(net "GND")
		)
		(pad "269" smd rect
			(at -4.59994 110.499906 270)
			(size 1.8034 0.508)
			(layers "B.Cu" "B.Mask" "B.Paste")
			(net "M_E_DQ<55>")
		)
		(pad "270" smd rect
			(at -4.59994 111.350044 270)
			(size 1.8034 0.508)
			(layers "B.Cu" "B.Mask" "B.Paste")
			(net "GND")
		)
		(pad "271" smd rect
			(at -4.59994 112.199928 270)
			(size 1.8034 0.508)
			(layers "B.Cu" "B.Mask" "B.Paste")
			(net "M_E_DQ<51>")
		)
		(pad "272" smd rect
			(at -4.59994 113.050066 270)
			(size 1.8034 0.508)
			(layers "B.Cu" "B.Mask" "B.Paste")
			(net "GND")
		)
		(pad "273" smd rect
			(at -4.59994 113.89995 270)
			(size 1.8034 0.508)
			(layers "B.Cu" "B.Mask" "B.Paste")
			(net "M_E_DQ<61>")
		)
		(pad "274" smd rect
			(at -4.59994 114.750088 270)
			(size 1.8034 0.508)
			(layers "B.Cu" "B.Mask" "B.Paste")
			(net "GND")
		)
		(pad "275" smd rect
			(at -4.59994 115.599972 270)
			(size 1.8034 0.508)
			(layers "B.Cu" "B.Mask" "B.Paste")
			(net "M_E_DQ<57>")
		)
		(pad "276" smd rect
			(at -4.59994 116.45011 270)
			(size 1.8034 0.508)
			(layers "B.Cu" "B.Mask" "B.Paste")
			(net "GND")
		)
		(pad "277" smd rect
			(at -4.59994 117.299994 270)
			(size 1.8034 0.508)
			(layers "B.Cu" "B.Mask" "B.Paste")
			(net "M_E_DQS_DN<7>")
		)
		(pad "278" smd rect
			(at -4.59994 118.149878 270)
			(size 1.8034 0.508)
			(layers "B.Cu" "B.Mask" "B.Paste")
			(net "M_E_DQS_DP<7>")
		)
		(pad "279" smd rect
			(at -4.59994 119.000016 270)
			(size 1.8034 0.508)
			(layers "B.Cu" "B.Mask" "B.Paste")
			(net "GND")
		)
		(pad "280" smd rect
			(at -4.59994 119.8499 270)
			(size 1.8034 0.508)
			(layers "B.Cu" "B.Mask" "B.Paste")
			(net "M_E_DQ<63>")
		)
		(pad "281" smd rect
			(at -4.59994 120.700038 270)
			(size 1.8034 0.508)
			(layers "B.Cu" "B.Mask" "B.Paste")
			(net "GND")
		)
		(pad "282" smd rect
			(at -4.59994 121.549922 270)
			(size 1.8034 0.508)
			(layers "B.Cu" "B.Mask" "B.Paste")
			(net "M_E_DQ<59>")
		)
		(pad "283" smd rect
			(at -4.59994 122.40006 270)
			(size 1.8034 0.508)
			(layers "B.Cu" "B.Mask" "B.Paste")
			(net "GND")
		)
		(pad "284" smd rect
			(at -4.59994 123.249944 270)
			(size 1.8034 0.508)
			(layers "B.Cu" "B.Mask" "B.Paste")
			(net "PVPP_DEF")
		)
		(pad "285" smd rect
			(at -4.59994 124.100082 270)
			(size 1.8034 0.508)
			(layers "B.Cu" "B.Mask" "B.Paste")
			(net "SMB_DDR_DEF_VPP_SDA")
		)
		(pad "286" smd rect
			(at -4.59994 124.949966 270)
			(size 1.8034 0.508)
			(layers "B.Cu" "B.Mask" "B.Paste")
			(net "PVPP_DEF")
		)
		(pad "287" smd rect
			(at -4.59994 125.800104 270)
			(size 1.8034 0.508)
			(layers "B.Cu" "B.Mask" "B.Paste")
			(net "PVPP_DEF")
		)
		(pad "288" smd rect
			(at -4.59994 126.649988 270)
			(size 1.8034 0.508)
			(layers "B.Cu" "B.Mask" "B.Paste")
			(net "PVPP_DEF")
		)
	)
)
